(kicad_pcb
	(version 20240108)
	(generator "pcbnew")
	(generator_version "8.0")
	(general
		(thickness 1.62)
		(legacy_teardrops no)
	)
	(paper "A4")
	(title_block
		(title "Jetson Orin Baseboard")
		(date "2025-03-12")
		(rev "1.3.4")
		(company "Antmicro Ltd")
		(comment 1 "www.antmicro.com")
		(comment 9 "footprints 187-191 of 677")
	)
	(layers
		(0 "F.Cu" signal)
		(1 "In1.Cu" signal)
		(2 "In2.Cu" signal)
		(3 "In3.Cu" signal)
		(4 "In4.Cu" jumper)
		(5 "In5.Cu" signal)
		(6 "In6.Cu" signal)
		(31 "B.Cu" signal)
		(32 "B.Adhes" user "B.Adhesive")
		(33 "F.Adhes" user "F.Adhesive")
		(34 "B.Paste" user)
		(35 "F.Paste" user)
		(36 "B.SilkS" user "B.Silkscreen")
		(37 "F.SilkS" user "F.Silkscreen")
		(38 "B.Mask" user)
		(39 "F.Mask" user)
		(40 "Dwgs.User" user "User.Drawings")
		(41 "Cmts.User" user "User.Comments")
		(42 "Eco1.User" user "User.Eco1")
		(43 "Eco2.User" user "User.Eco2")
		(44 "Edge.Cuts" user)
		(45 "Margin" user)
		(46 "B.CrtYd" user "B.Courtyard")
		(47 "F.CrtYd" user "F.Courtyard")
		(48 "B.Fab" user)
		(49 "F.Fab" user)
	)
	(footprint "antmicro-footprints:R_0402_1005Metric"
		(layer "F.Cu")
		(at 66.5 119 90)
		(descr "Resistor SMD 0402")
		(tags "resistor SMD 0402")
		(property "Reference" "R99"
			(at -2.95 0.45 90)
			(layer "F.SilkS")
			(effects
				(font
					(size 0.7 0.7)
					(thickness 0.15)
				)
				(justify left bottom)
			)
		)
		(property "Value" "R_10k_0402"
			(at 0 1.4 90)
			(layer "F.Fab")
			(effects
				(font
					(size 0.7 0.7)
					(thickness 0.15)
				)
				(justify left bottom)
			)
		)
		(property "Footprint" "antmicro-footprints:R_0402_1005Metric"
			(at 0 0 90)
			(layer "F.Fab")
			(hide yes)
			(effects
				(font
					(size 1.27 1.27)
					(thickness 0.15)
				)
			)
		)
		(property "Datasheet" "https://www.bourns.com/docs/product-datasheets/cr.pdf"
			(at 0 0 90)
			(layer "F.Fab")
			(hide yes)
			(effects
				(font
					(size 1.27 1.27)
					(thickness 0.15)
				)
			)
		)
		(property "Author" "Antmicro"
			(at 185.5 52.5 0)
			(layer "F.Fab")
			(hide yes)
			(effects
				(font
					(size 1 1)
					(thickness 0.15)
				)
			)
		)
		(property "License" "Apache-2.0"
			(at 185.5 52.5 0)
			(layer "F.Fab")
			(hide yes)
			(effects
				(font
					(size 1 1)
					(thickness 0.15)
				)
			)
		)
		(property "MPN" "CR0402-FX-1002GLF"
			(at 185.5 52.5 0)
			(layer "F.Fab")
			(hide yes)
			(effects
				(font
					(size 1 1)
					(thickness 0.15)
				)
			)
		)
		(property "Manufacturer" "Bourns"
			(at 185.5 52.5 0)
			(layer "F.Fab")
			(hide yes)
			(effects
				(font
					(size 1 1)
					(thickness 0.15)
				)
			)
		)
		(property "Tolerance" "1%"
			(at 185.5 52.5 0)
			(layer "F.Fab")
			(hide yes)
			(effects
				(font
					(size 1 1)
					(thickness 0.15)
				)
			)
		)
		(property "Val" "10k"
			(at 185.5 52.5 0)
			(layer "F.Fab")
			(hide yes)
			(effects
				(font
					(size 1 1)
					(thickness 0.15)
				)
			)
		)
		(sheetname "USB Debug, DP")
		(sheetfile "usb.kicad_sch")
		(attr smd)
		(fp_rect
			(start -0.925 -0.47)
			(end 0.925 0.47)
			(stroke
				(width 0.05)
				(type default)
			)
			(fill none)
			(layer "F.CrtYd")
		)
		(fp_rect
			(start -0.5 -0.25)
			(end 0.5 0.25)
			(stroke
				(width 0.15)
				(type solid)
			)
			(fill none)
			(layer "F.Fab")
		)
		(fp_text user "License: Apache-2.0"
			(at -0.95 5.169 90)
			(layer "F.Fab")
			(hide yes)
			(effects
				(font
					(size 0.7 0.7)
					(thickness 0.15)
				)
				(justify left bottom)
			)
		)
		(fp_text user "Author: Antmicro"
			(at -0.95 4.169 90)
			(layer "F.Fab")
			(hide yes)
			(effects
				(font
					(size 0.7 0.7)
					(thickness 0.15)
				)
				(justify left bottom)
			)
		)
		(fp_text user "${REFERENCE}"
			(at -0.95 3.168 90)
			(layer "F.Fab")
			(hide yes)
			(effects
				(font
					(size 0.7 0.7)
					(thickness 0.15)
				)
				(justify left bottom)
			)
		)
		(pad "1" smd roundrect
			(at -0.48 0 90)
			(size 0.59 0.64)
			(layers "F.Cu" "F.Paste" "F.Mask")
			(roundrect_rratio 0.25)
			(net 1 "GND")
			(pintype "passive")
		)
		(pad "2" smd roundrect
			(at 0.48 0 90)
			(size 0.59 0.64)
			(layers "F.Cu" "F.Paste" "F.Mask")
			(roundrect_rratio 0.25)
			(net 673 "Net-(U12-EN)")
			(pintype "passive")
		)
	)
	(footprint "antmicro-footprints:R_0402_1005Metric"
		(layer "F.Cu")
		(at 110.8 102.65 -90)
		(descr "Resistor SMD 0402")
		(tags "resistor SMD 0402")
		(property "Reference" "R124"
			(at -0.85 -0.06 -90)
			(layer "F.SilkS")
			(effects
				(font
					(size 0.7 0.7)
					(thickness 0.15)
				)
				(justify left bottom)
			)
		)
		(property "Value" "R_0R_0402"
			(at 0 1.4 -90)
			(layer "F.Fab")
			(effects
				(font
					(size 0.7 0.7)
					(thickness 0.15)
				)
				(justify left bottom)
			)
		)
		(property "Footprint" "antmicro-footprints:R_0402_1005Metric"
			(at 0 0 -90)
			(layer "F.Fab")
			(hide yes)
			(effects
				(font
					(size 1.27 1.27)
					(thickness 0.15)
				)
			)
		)
		(property "Datasheet" "https://industrial.panasonic.com/cdbs/www-data/pdf/RDA0000/AOA0000C301.pdf"
			(at 0 0 -90)
			(layer "F.Fab")
			(hide yes)
			(effects
				(font
					(size 1.27 1.27)
					(thickness 0.15)
				)
			)
		)
		(property "Author" "Antmicro"
			(at 8.15 213.45 0)
			(layer "F.Fab")
			(hide yes)
			(effects
				(font
					(size 1 1)
					(thickness 0.15)
				)
			)
		)
		(property "Current" "1A"
			(at 8.15 213.45 0)
			(layer "F.Fab")
			(hide yes)
			(effects
				(font
					(size 1 1)
					(thickness 0.15)
				)
			)
		)
		(property "License" "Apache-2.0"
			(at 8.15 213.45 0)
			(layer "F.Fab")
			(hide yes)
			(effects
				(font
					(size 1 1)
					(thickness 0.15)
				)
			)
		)
		(property "MPN" "ERJ2GE0R00X"
			(at 8.15 213.45 0)
			(layer "F.Fab")
			(hide yes)
			(effects
				(font
					(size 1 1)
					(thickness 0.15)
				)
			)
		)
		(property "Manufacturer" "Panasonic"
			(at 8.15 213.45 0)
			(layer "F.Fab")
			(hide yes)
			(effects
				(font
					(size 1 1)
					(thickness 0.15)
				)
			)
		)
		(property "Tolerance" ""
			(at 8.15 213.45 0)
			(layer "F.Fab")
			(hide yes)
			(effects
				(font
					(size 1 1)
					(thickness 0.15)
				)
			)
		)
		(property "Val" "0R"
			(at 8.15 213.45 0)
			(layer "F.Fab")
			(hide yes)
			(effects
				(font
					(size 1 1)
					(thickness 0.15)
				)
			)
		)
		(sheetname "USB3")
		(sheetfile "usb3.kicad_sch")
		(attr smd exclude_from_pos_files exclude_from_bom dnp)
		(fp_rect
			(start -0.925 -0.47)
			(end 0.925 0.47)
			(stroke
				(width 0.05)
				(type default)
			)
			(fill none)
			(layer "F.CrtYd")
		)
		(fp_rect
			(start -0.5 -0.25)
			(end 0.5 0.25)
			(stroke
				(width 0.15)
				(type solid)
			)
			(fill none)
			(layer "F.Fab")
		)
		(fp_text user "Author: Antmicro"
			(at -0.95 4.169 -90)
			(layer "F.Fab")
			(hide yes)
			(effects
				(font
					(size 0.7 0.7)
					(thickness 0.15)
				)
				(justify left bottom)
			)
		)
		(fp_text user "License: Apache-2.0"
			(at -0.95 5.169 -90)
			(layer "F.Fab")
			(hide yes)
			(effects
				(font
					(size 0.7 0.7)
					(thickness 0.15)
				)
				(justify left bottom)
			)
		)
		(fp_text user "${REFERENCE}"
			(at -0.95 3.168 -90)
			(layer "F.Fab")
			(hide yes)
			(effects
				(font
					(size 0.7 0.7)
					(thickness 0.15)
				)
				(justify left bottom)
			)
		)
		(pad "1" smd roundrect
			(at -0.48 0 270)
			(size 0.59 0.64)
			(layers "F.Cu" "F.Paste" "F.Mask")
			(roundrect_rratio 0.25)
			(net 251 "SYS_SDA")
			(pintype "passive")
		)
		(pad "2" smd roundrect
			(at 0.48 0 270)
			(size 0.59 0.64)
			(layers "F.Cu" "F.Paste" "F.Mask")
			(roundrect_rratio 0.25)
			(net 362 "/USB3/USBC1_I2C_SDA")
			(pintype "passive")
		)
	)
	(footprint "antmicro-footprints:C_0402_1005Metric"
		(layer "F.Cu")
		(at 147.3 119.3)
		(descr "Capacitor SMD 0402")
		(tags "capacitor SMD 0402")
		(property "Reference" "C115"
			(at -1.4 1.3 0)
			(layer "F.SilkS")
			(effects
				(font
					(size 0.7 0.7)
					(thickness 0.15)
				)
				(justify left bottom)
			)
		)
		(property "Value" "C_1u_0402"
			(at 0 1.4 0)
			(layer "F.Fab")
			(effects
				(font
					(size 0.7 0.7)
					(thickness 0.15)
				)
				(justify left bottom)
			)
		)
		(property "Footprint" "antmicro-footprints:C_0402_1005Metric"
			(at 0 0 0)
			(layer "F.Fab")
			(hide yes)
			(effects
				(font
					(size 1.27 1.27)
					(thickness 0.15)
				)
			)
		)
		(property "Datasheet" "https://product.tdk.com/en/search/capacitor/ceramic/mlcc/info?part_no=C1005X6S1A105K050BC"
			(at 0 0 0)
			(layer "F.Fab")
			(hide yes)
			(effects
				(font
					(size 1.27 1.27)
					(thickness 0.15)
				)
			)
		)
		(property "Author" "Antmicro"
			(at 0 0 0)
			(layer "F.Fab")
			(hide yes)
			(effects
				(font
					(size 1 1)
					(thickness 0.15)
				)
			)
		)
		(property "Dielectric" ""
			(at 0 0 0)
			(layer "F.Fab")
			(hide yes)
			(effects
				(font
					(size 1 1)
					(thickness 0.15)
				)
			)
		)
		(property "License" "Apache-2.0"
			(at 0 0 0)
			(layer "F.Fab")
			(hide yes)
			(effects
				(font
					(size 1 1)
					(thickness 0.15)
				)
			)
		)
		(property "MPN" "C1005X6S1A105K050BC"
			(at 0 0 0)
			(layer "F.Fab")
			(hide yes)
			(effects
				(font
					(size 1 1)
					(thickness 0.15)
				)
			)
		)
		(property "Manufacturer" "TDK"
			(at 0 0 0)
			(layer "F.Fab")
			(hide yes)
			(effects
				(font
					(size 1 1)
					(thickness 0.15)
				)
			)
		)
		(property "Val" "1u"
			(at 0 0 0)
			(layer "F.Fab")
			(hide yes)
			(effects
				(font
					(size 1 1)
					(thickness 0.15)
				)
			)
		)
		(property "Voltage" ""
			(at 0 0 0)
			(layer "F.Fab")
			(hide yes)
			(effects
				(font
					(size 1 1)
					(thickness 0.15)
				)
			)
		)
		(sheetname "Peripherals")
		(sheetfile "peripherals.kicad_sch")
		(attr smd)
		(fp_rect
			(start -0.925 -0.47)
			(end 0.925 0.47)
			(stroke
				(width 0.05)
				(type default)
			)
			(fill none)
			(layer "F.CrtYd")
		)
		(fp_line
			(start -0.494 -0.25)
			(end 0.504 -0.25)
			(stroke
				(width 0.15)
				(type solid)
			)
			(layer "F.Fab")
		)
		(fp_line
			(start -0.494 0.248)
			(end -0.494 -0.25)
			(stroke
				(width 0.15)
				(type solid)
			)
			(layer "F.Fab")
		)
		(fp_line
			(start 0.504 -0.25)
			(end 0.504 0.248)
			(stroke
				(width 0.15)
				(type solid)
			)
			(layer "F.Fab")
		)
		(fp_line
			(start 0.504 0.248)
			(end -0.494 0.248)
			(stroke
				(width 0.15)
				(type solid)
			)
			(layer "F.Fab")
		)
		(fp_text user "License: Apache-2.0"
			(at -0.932 5.17 0)
			(layer "F.Fab")
			(hide yes)
			(effects
				(font
					(size 0.7 0.7)
					(thickness 0.15)
				)
				(justify left bottom)
			)
		)
		(fp_text user "${REFERENCE}"
			(at -0.932 3.168 0)
			(layer "F.Fab")
			(hide yes)
			(effects
				(font
					(size 0.7 0.7)
					(thickness 0.15)
				)
				(justify left bottom)
			)
		)
		(fp_text user "Author: Antmicro"
			(at -0.932 4.17 0)
			(layer "F.Fab")
			(hide yes)
			(effects
				(font
					(size 0.7 0.7)
					(thickness 0.15)
				)
				(justify left bottom)
			)
		)
		(pad "1" smd roundrect
			(at -0.48 0)
			(size 0.59 0.64)
			(layers "F.Cu" "F.Paste" "F.Mask")
			(roundrect_rratio 0.25)
			(net 485 "/Peripherals/VCC_CONN")
			(pintype "passive")
		)
		(pad "2" smd roundrect
			(at 0.48 0)
			(size 0.59 0.64)
			(layers "F.Cu" "F.Paste" "F.Mask")
			(roundrect_rratio 0.25)
			(net 1 "GND")
			(pintype "passive")
		)
	)
	(footprint "antmicro-footprints:R_0402_1005Metric"
		(layer "F.Cu")
		(at 107.64 124.8 90)
		(descr "Resistor SMD 0402")
		(tags "resistor SMD 0402")
		(property "Reference" "R140"
			(at 2.725 0.435 90)
			(layer "F.SilkS")
			(effects
				(font
					(size 0.7 0.7)
					(thickness 0.15)
				)
				(justify left bottom)
			)
		)
		(property "Value" "R_470R_0402"
			(at 0 1.4 90)
			(layer "F.Fab")
			(effects
				(font
					(size 0.7 0.7)
					(thickness 0.15)
				)
				(justify left bottom)
			)
		)
		(property "Footprint" "antmicro-footprints:R_0402_1005Metric"
			(at 0 0 90)
			(layer "F.Fab")
			(hide yes)
			(effects
				(font
					(size 1.27 1.27)
					(thickness 0.15)
				)
			)
		)
		(property "Datasheet" "https://www.bourns.com/docs/product-datasheets/cr.pdf"
			(at 0 0 90)
			(layer "F.Fab")
			(hide yes)
			(effects
				(font
					(size 1.27 1.27)
					(thickness 0.15)
				)
			)
		)
		(property "Author" "Antmicro"
			(at 232.44 17.16 0)
			(layer "F.Fab")
			(hide yes)
			(effects
				(font
					(size 1 1)
					(thickness 0.15)
				)
			)
		)
		(property "License" "Apache-2.0"
			(at 232.44 17.16 0)
			(layer "F.Fab")
			(hide yes)
			(effects
				(font
					(size 1 1)
					(thickness 0.15)
				)
			)
		)
		(property "MPN" "CR0402-FX-4700GLF"
			(at 232.44 17.16 0)
			(layer "F.Fab")
			(hide yes)
			(effects
				(font
					(size 1 1)
					(thickness 0.15)
				)
			)
		)
		(property "Manufacturer" "Bourns"
			(at 232.44 17.16 0)
			(layer "F.Fab")
			(hide yes)
			(effects
				(font
					(size 1 1)
					(thickness 0.15)
				)
			)
		)
		(property "Tolerance" "1%"
			(at 232.44 17.16 0)
			(layer "F.Fab")
			(hide yes)
			(effects
				(font
					(size 1 1)
					(thickness 0.15)
				)
			)
		)
		(property "Val" "470R"
			(at 232.44 17.16 0)
			(layer "F.Fab")
			(hide yes)
			(effects
				(font
					(size 1 1)
					(thickness 0.15)
				)
			)
		)
		(sheetname "USB3")
		(sheetfile "usb3.kicad_sch")
		(attr smd)
		(fp_rect
			(start -0.925 -0.47)
			(end 0.925 0.47)
			(stroke
				(width 0.05)
				(type default)
			)
			(fill none)
			(layer "F.CrtYd")
		)
		(fp_rect
			(start -0.5 -0.25)
			(end 0.5 0.25)
			(stroke
				(width 0.15)
				(type solid)
			)
			(fill none)
			(layer "F.Fab")
		)
		(fp_text user "${REFERENCE}"
			(at -0.95 3.168 90)
			(layer "F.Fab")
			(hide yes)
			(effects
				(font
					(size 0.7 0.7)
					(thickness 0.15)
				)
				(justify left bottom)
			)
		)
		(fp_text user "License: Apache-2.0"
			(at -0.95 5.169 90)
			(layer "F.Fab")
			(hide yes)
			(effects
				(font
					(size 0.7 0.7)
					(thickness 0.15)
				)
				(justify left bottom)
			)
		)
		(fp_text user "Author: Antmicro"
			(at -0.95 4.169 90)
			(layer "F.Fab")
			(hide yes)
			(effects
				(font
					(size 0.7 0.7)
					(thickness 0.15)
				)
				(justify left bottom)
			)
		)
		(pad "1" smd roundrect
			(at -0.48 0 90)
			(size 0.59 0.64)
			(layers "F.Cu" "F.Paste" "F.Mask")
			(roundrect_rratio 0.25)
			(net 150 "Net-(D11-A)")
			(pintype "passive")
		)
		(pad "2" smd roundrect
			(at 0.48 0 90)
			(size 0.59 0.64)
			(layers "F.Cu" "F.Paste" "F.Mask")
			(roundrect_rratio 0.25)
			(net 270 "/USB3/USBC1_VBUS")
			(pintype "passive")
		)
	)
	(footprint "antmicro-footprints:C_0402_1005Metric"
		(layer "F.Cu")
		(at 60.7 109.4 -90)
		(descr "Capacitor SMD 0402")
		(tags "capacitor SMD 0402")
		(property "Reference" "C45"
			(at 1.15 0.35 -90)
			(layer "F.SilkS")
			(effects
				(font
					(size 0.7 0.7)
					(thickness 0.15)
				)
				(justify left bottom)
			)
		)
		(property "Value" "C_100n_0402"
			(at 0 1.4 -90)
			(layer "F.Fab")
			(effects
				(font
					(size 0.7 0.7)
					(thickness 0.15)
				)
				(justify left bottom)
			)
		)
		(property "Footprint" "antmicro-footprints:C_0402_1005Metric"
			(at 0 0 -90)
			(layer "F.Fab")
			(hide yes)
			(effects
				(font
					(size 1.27 1.27)
					(thickness 0.15)
				)
			)
		)
		(property "Datasheet" "https://www.murata.com/products/productdetail?partno=GRM155R61H104KE14%23"
			(at 0 0 -90)
			(layer "F.Fab")
			(hide yes)
			(effects
				(font
					(size 1.27 1.27)
					(thickness 0.15)
				)
			)
		)
		(property "Author" "Antmicro"
			(at -48.7 170.1 0)
			(layer "F.Fab")
			(hide yes)
			(effects
				(font
					(size 1 1)
					(thickness 0.15)
				)
			)
		)
		(property "Dielectric" "X5R"
			(at -48.7 170.1 0)
			(layer "F.Fab")
			(hide yes)
			(effects
				(font
					(size 1 1)
					(thickness 0.15)
				)
			)
		)
		(property "License" "Apache-2.0"
			(at -48.7 170.1 0)
			(layer "F.Fab")
			(hide yes)
			(effects
				(font
					(size 1 1)
					(thickness 0.15)
				)
			)
		)
		(property "MPN" "GRM155R61H104KE14D"
			(at -48.7 170.1 0)
			(layer "F.Fab")
			(hide yes)
			(effects
				(font
					(size 1 1)
					(thickness 0.15)
				)
			)
		)
		(property "Manufacturer" "Murata"
			(at -48.7 170.1 0)
			(layer "F.Fab")
			(hide yes)
			(effects
				(font
					(size 1 1)
					(thickness 0.15)
				)
			)
		)
		(property "Val" "100n"
			(at -48.7 170.1 0)
			(layer "F.Fab")
			(hide yes)
			(effects
				(font
					(size 1 1)
					(thickness 0.15)
				)
			)
		)
		(property "Voltage" "50V"
			(at -48.7 170.1 0)
			(layer "F.Fab")
			(hide yes)
			(effects
				(font
					(size 1 1)
					(thickness 0.15)
				)
			)
		)
		(sheetname "USB Debug, DP")
		(sheetfile "usb.kicad_sch")
		(attr smd)
		(fp_rect
			(start -0.925 -0.47)
			(end 0.925 0.47)
			(stroke
				(width 0.05)
				(type default)
			)
			(fill none)
			(layer "F.CrtYd")
		)
		(fp_line
			(start -0.494 0.248)
			(end -0.494 -0.25)
			(stroke
				(width 0.15)
				(type solid)
			)
			(layer "F.Fab")
		)
		(fp_line
			(start 0.504 0.248)
			(end -0.494 0.248)
			(stroke
				(width 0.15)
				(type solid)
			)
			(layer "F.Fab")
		)
		(fp_line
			(start -0.494 -0.25)
			(end 0.504 -0.25)
			(stroke
				(width 0.15)
				(type solid)
			)
			(layer "F.Fab")
		)
		(fp_line
			(start 0.504 -0.25)
			(end 0.504 0.248)
			(stroke
				(width 0.15)
				(type solid)
			)
			(layer "F.Fab")
		)
		(fp_text user "Author: Antmicro"
			(at -0.932 4.17 -90)
			(layer "F.Fab")
			(hide yes)
			(effects
				(font
					(size 0.7 0.7)
					(thickness 0.15)
				)
				(justify left bottom)
			)
		)
		(fp_text user "${REFERENCE}"
			(at -0.932 3.168 -90)
			(layer "F.Fab")
			(hide yes)
			(effects
				(font
					(size 0.7 0.7)
					(thickness 0.15)
				)
				(justify left bottom)
			)
		)
		(fp_text user "License: Apache-2.0"
			(at -0.932 5.17 -90)
			(layer "F.Fab")
			(hide yes)
			(effects
				(font
					(size 0.7 0.7)
					(thickness 0.15)
				)
				(justify left bottom)
			)
		)
		(pad "1" smd roundrect
			(at -0.48 0 270)
			(size 0.59 0.64)
			(layers "F.Cu" "F.Paste" "F.Mask")
			(roundrect_rratio 0.25)
			(net 99 "+5V")
			(pintype "passive")
		)
		(pad "2" smd roundrect
			(at 0.48 0 270)
			(size 0.59 0.64)
			(layers "F.Cu" "F.Paste" "F.Mask")
			(roundrect_rratio 0.25)
			(net 1 "GND")
			(pintype "passive")
		)
	)
)
